(kicad_pcb
	(version 20260206)
	(generator "pcbnew")
	(generator_version "10.0")
	(general
		(thickness 1.6)
		(legacy_teardrops no)
	)
	(paper "A4")
	(title_block
		(title "Bryce Canyon_IOM_M2_16342-2_OCP.brd")
		(comment 1 "Bryce Canyon / footprints 697-704 of 1146")
	)
	(layers
		(0 "F.Cu" signal "TOP")
		(4 "In1.Cu" signal "L2GND")
		(6 "In2.Cu" signal "L3")
		(8 "In3.Cu" signal "L4VCC")
		(10 "In4.Cu" signal "L5VCC")
		(12 "In5.Cu" signal "L6")
		(14 "In6.Cu" signal "L7GND")
		(2 "B.Cu" signal "BOTTOM")
		(9 "F.Adhes" user "F.Adhesive")
		(11 "B.Adhes" user "B.Adhesive")
		(13 "F.Paste" user "Package Geometry/Pastemask Top")
		(15 "B.Paste" user "Package Geometry/Pastemask Bottom")
		(5 "F.SilkS" user "Ref Des/Silkscreen Top")
		(7 "B.SilkS" user "Ref Des/Silkscreen Bottom")
		(1 "F.Mask" user "Board Geometry/Soldermask Top")
		(3 "B.Mask" user "Board Geometry/Soldermask Bottom")
		(17 "Dwgs.User" user "User.Drawings")
		(19 "Cmts.User" user "User.Comments")
		(21 "Eco1.User" user "User.Eco1")
		(23 "Eco2.User" user "User.Eco2")
		(25 "Edge.Cuts" user "Board Geometry/Outline")
		(27 "Margin" user)
		(31 "F.CrtYd" user "Package Geometry/Place Bound Top")
		(29 "B.CrtYd" user "Package Geometry/Place Bound Bottom")
		(35 "F.Fab" user "Ref Des/Assembly Top")
		(33 "B.Fab" user "Ref Des/Assembly Bottom")
	)
	(footprint ""
		(layer "F.Cu")
		(at 99.3902 -153.7716 -90)
		(property "Reference" "R19"
			(at 0 0 270)
			(layer "F.SilkS")
			(hide yes)
			(effects
				(font
					(size 1.27 1.27)
				)
			)
		)
		(property "Value" "4K7R2F-GP"
			(at 0.064008 -3.993896 270)
			(unlocked yes)
			(layer "F.Fab")
			(hide yes)
			(effects
				(font
					(size 1.016 1.016)
					(thickness 0.1524)
				)
			)
		)
		(property "Device Type" "R402H16"
			(at 0.064008 -5.517896 270)
			(unlocked yes)
			(layer "F.Fab")
			(hide yes)
			(effects
				(font
					(size 1.016 1.016)
					(thickness 0.1524)
				)
			)
		)
		(duplicate_pad_numbers_are_jumpers no)
		(fp_line
			(start -0.508 -0.9398)
			(end -0.508 0.9398)
			(stroke
				(width 0.1524)
				(type default)
			)
			(layer "F.SilkS")
		)
		(fp_line
			(start 0.508 -0.9398)
			(end -0.508 -0.9398)
			(stroke
				(width 0.1524)
				(type default)
			)
			(layer "F.SilkS")
		)
		(fp_rect
			(start -0.508 0.9398)
			(end 0.508 -0.9398)
			(stroke
				(width 0)
				(type default)
			)
			(fill no)
			(layer "F.CrtYd")
		)
		(fp_rect
			(start -0.508 0.9398)
			(end 0.508 -0.9398)
			(stroke
				(width 0)
				(type default)
			)
			(fill no)
			(layer "F.Fab")
		)
		(pad "1" smd custom
			(at 0 -0.4445 270)
			(size 0.1397 0.1397)
			(layers "F.Cu" "F.Mask" "F.Paste")
			(net "P3V3_STBY")
			(options
				(clearance outline)
				(anchor circle)
			)
			(primitives
				(gr_poly
					(pts
						(arc
							(start -0.1778 -0.2794)
							(mid -0.249642 -0.249642)
							(end -0.2794 -0.1778)
						)
						(arc
							(start -0.2794 0.1778)
							(mid -0.249642 0.249642)
							(end -0.1778 0.2794)
						)
						(arc
							(start 0.1778 0.2794)
							(mid 0.249642 0.249642)
							(end 0.2794 0.1778)
						)
						(arc
							(start 0.2794 -0.1778)
							(mid 0.249642 -0.249642)
							(end 0.1778 -0.2794)
						)
					)
					(width 0)
					(fill yes)
				)
			)
		)
		(pad "2" smd custom
			(at 0 0.4445 270)
			(size 0.1397 0.1397)
			(layers "F.Cu" "F.Mask" "F.Paste")
			(net "CFG_SEL0")
			(options
				(clearance outline)
				(anchor circle)
			)
			(primitives
				(gr_poly
					(pts
						(arc
							(start -0.1778 -0.2794)
							(mid -0.249642 -0.249642)
							(end -0.2794 -0.1778)
						)
						(arc
							(start -0.2794 0.1778)
							(mid -0.249642 0.249642)
							(end -0.1778 0.2794)
						)
						(arc
							(start 0.1778 0.2794)
							(mid 0.249642 0.249642)
							(end 0.2794 0.1778)
						)
						(arc
							(start 0.2794 -0.1778)
							(mid 0.249642 -0.249642)
							(end 0.1778 -0.2794)
						)
					)
					(width 0)
					(fill yes)
				)
			)
		)
	)
	(footprint ""
		(layer "F.Cu")
		(at 162.089338 -10.847578 90)
		(property "Reference" "L10"
			(at 0 0 90)
			(layer "F.SilkS")
			(hide yes)
			(effects
				(font
					(size 1.27 1.27)
				)
			)
		)
		(property "Value" "COIL-3D3UH-48-GP"
			(at -3.8735 -3.048 90)
			(unlocked yes)
			(layer "F.Fab")
			(hide yes)
			(effects
				(font
					(size 1.016 1.016)
					(thickness 0.1524)
				)
			)
		)
		(property "Device Type" "L4947-1215H119"
			(at -3.8735 -4.572 90)
			(unlocked yes)
			(layer "F.Fab")
			(hide yes)
			(effects
				(font
					(size 1.016 1.016)
					(thickness 0.1524)
				)
			)
		)
		(duplicate_pad_numbers_are_jumpers no)
		(fp_line
			(start 2.6035 -3.429)
			(end 2.6035 3.429)
			(stroke
				(width 0.1524)
				(type default)
			)
			(layer "F.SilkS")
		)
		(fp_line
			(start -2.6035 -3.429)
			(end 2.6035 -3.429)
			(stroke
				(width 0.1524)
				(type default)
			)
			(layer "F.SilkS")
		)
		(fp_line
			(start 2.6035 3.429)
			(end -2.6035 3.429)
			(stroke
				(width 0.1524)
				(type default)
			)
			(layer "F.SilkS")
		)
		(fp_line
			(start -2.6035 3.429)
			(end -2.6035 -3.429)
			(stroke
				(width 0.1524)
				(type default)
			)
			(layer "F.SilkS")
		)
		(fp_rect
			(start -2.3495 2.4257)
			(end 2.3495 -2.4257)
			(stroke
				(width 0)
				(type default)
			)
			(fill no)
			(layer "F.CrtYd")
		)
		(fp_poly
			(pts
				(xy -2.8575 3.5052) (xy -2.8575 2.4257) (xy 2.3495 2.4257) (xy 2.3495 -2.4257) (xy -2.3495 -2.4257)
				(xy -2.3495 2.413) (xy -2.8575 2.413) (xy -2.8575 -3.5052) (xy 2.8575 -3.5052) (xy 2.8575 3.5052)
			)
			(stroke
				(width 0)
				(type default)
			)
			(fill no)
			(layer "F.CrtYd")
		)
		(fp_rect
			(start -2.8575 3.5052)
			(end 2.8575 -3.5052)
			(stroke
				(width 0)
				(type default)
			)
			(fill no)
			(layer "F.Fab")
		)
		(pad "1" smd rect
			(at 0 -1.999996 90)
			(size 2.0066 2.3622)
			(layers "F.Cu" "F.Mask" "F.Paste")
			(net "P1V8_STBY_SW")
		)
		(pad "2" smd rect
			(at 0 1.999996 90)
			(size 2.0066 2.3622)
			(layers "F.Cu" "F.Mask" "F.Paste")
			(net "P1V8_STBY")
		)
	)
	(footprint ""
		(layer "F.Cu")
		(at 71.890128 -186.292744 180)
		(property "Reference" "C197"
			(at 0 0 180)
			(layer "F.SilkS")
			(hide yes)
			(effects
				(font
					(size 1.27 1.27)
				)
			)
		)
		(property "Value" "SC1U16V3KX-5GP"
			(at 0 -2.8194 180)
			(unlocked yes)
			(layer "F.Fab")
			(hide yes)
			(effects
				(font
					(size 1.016 1.016)
					(thickness 0.1524)
				)
			)
		)
		(property "Device Type" "C603H36"
			(at 0 -4.3434 180)
			(unlocked yes)
			(layer "F.Fab")
			(hide yes)
			(effects
				(font
					(size 1.016 1.016)
					(thickness 0.1524)
				)
			)
		)
		(duplicate_pad_numbers_are_jumpers no)
		(fp_line
			(start 0.508 0)
			(end -0.508 0)
			(stroke
				(width 0.2032)
				(type default)
			)
			(layer "F.SilkS")
		)
		(fp_rect
			(start -0.5842 1.3335)
			(end 0.5842 -1.3335)
			(stroke
				(width 0)
				(type default)
			)
			(fill no)
			(layer "F.CrtYd")
		)
		(fp_rect
			(start -0.5842 1.3335)
			(end 0.5842 -1.3335)
			(stroke
				(width 0)
				(type default)
			)
			(fill no)
			(layer "F.Fab")
		)
		(pad "1" smd custom
			(at 0 -0.762 180)
			(size 0.2159 0.2159)
			(layers "F.Cu" "F.Mask" "F.Paste")
			(net "TPS74801_P2V5_STBY_BIAS")
			(options
				(clearance outline)
				(anchor circle)
			)
			(primitives
				(gr_poly
					(pts
						(arc
							(start -0.3302 -0.4318)
							(mid -0.402042 -0.402042)
							(end -0.4318 -0.3302)
						)
						(arc
							(start -0.4318 0.3302)
							(mid -0.402042 0.402042)
							(end -0.3302 0.4318)
						)
						(arc
							(start 0.3302 0.4318)
							(mid 0.402042 0.402042)
							(end 0.4318 0.3302)
						)
						(arc
							(start 0.4318 -0.3302)
							(mid 0.402042 -0.402042)
							(end 0.3302 -0.4318)
						)
					)
					(width 0)
					(fill yes)
				)
			)
		)
		(pad "2" smd custom
			(at 0 0.762 180)
			(size 0.2159 0.2159)
			(layers "F.Cu" "F.Mask" "F.Paste")
			(net "GND")
			(options
				(clearance outline)
				(anchor circle)
			)
			(primitives
				(gr_poly
					(pts
						(arc
							(start -0.3302 -0.4318)
							(mid -0.402042 -0.402042)
							(end -0.4318 -0.3302)
						)
						(arc
							(start -0.4318 0.3302)
							(mid -0.402042 0.402042)
							(end -0.3302 0.4318)
						)
						(arc
							(start 0.3302 0.4318)
							(mid 0.402042 0.402042)
							(end 0.4318 0.3302)
						)
						(arc
							(start 0.4318 -0.3302)
							(mid 0.402042 -0.402042)
							(end 0.3302 -0.4318)
						)
					)
					(width 0)
					(fill yes)
				)
			)
		)
	)
	(footprint ""
		(layer "F.Cu")
		(at 62.769496 -158.270956 -90)
		(property "Reference" "L4"
			(at 0 0 270)
			(layer "F.SilkS")
			(hide yes)
			(effects
				(font
					(size 1.27 1.27)
				)
			)
		)
		(property "Value" "MMZ2012S601ATA1N-GP"
			(at 0 -4.2418 270)
			(unlocked yes)
			(layer "F.Fab")
			(hide yes)
			(effects
				(font
					(size 1.016 1.016)
					(thickness 0.1524)
				)
			)
		)
		(property "Device Type" "L805H42"
			(at 0 -5.7912 270)
			(unlocked yes)
			(layer "F.Fab")
			(hide yes)
			(effects
				(font
					(size 1.016 1.016)
					(thickness 0.1524)
				)
			)
		)
		(duplicate_pad_numbers_are_jumpers no)
		(fp_line
			(start -0.889 1.7018)
			(end -0.889 -1.7018)
			(stroke
				(width 0.1524)
				(type default)
			)
			(layer "F.SilkS")
		)
		(fp_line
			(start 0.889 1.7018)
			(end -0.889 1.7018)
			(stroke
				(width 0.1524)
				(type default)
			)
			(layer "F.SilkS")
		)
		(fp_line
			(start -0.889 -1.7018)
			(end 0.889 -1.7018)
			(stroke
				(width 0.1524)
				(type default)
			)
			(layer "F.SilkS")
		)
		(fp_line
			(start 0.889 -1.7018)
			(end 0.889 1.7018)
			(stroke
				(width 0.1524)
				(type default)
			)
			(layer "F.SilkS")
		)
		(fp_rect
			(start -0.9652 1.778)
			(end 0.9652 -1.778)
			(stroke
				(width 0)
				(type default)
			)
			(fill no)
			(layer "F.CrtYd")
		)
		(fp_rect
			(start -0.9652 1.778)
			(end 0.9652 -1.778)
			(stroke
				(width 0)
				(type default)
			)
			(fill no)
			(layer "F.Fab")
		)
		(pad "1" smd rect
			(at 0 -0.9652 270)
			(size 1.397 1.143)
			(layers "F.Cu" "F.Mask" "F.Paste")
			(net "P3V3_STBY")
		)
		(pad "2" smd rect
			(at 0 0.9652 270)
			(size 1.397 1.143)
			(layers "F.Cu" "F.Mask" "F.Paste")
			(net "VPLLAV33")
		)
	)
	(footprint ""
		(layer "F.Cu")
		(at 117.942868 -14.111732)
		(property "Reference" "R431"
			(at 0 0 0)
			(layer "F.SilkS")
			(hide yes)
			(effects
				(font
					(size 1.27 1.27)
				)
			)
		)
		(property "Value" "10R2F-L-GP"
			(at 0.064008 -3.993896 0)
			(unlocked yes)
			(layer "F.Fab")
			(hide yes)
			(effects
				(font
					(size 1.016 1.016)
					(thickness 0.1524)
				)
			)
		)
		(property "Device Type" "R402H14"
			(at 0.064008 -5.517896 0)
			(unlocked yes)
			(layer "F.Fab")
			(hide yes)
			(effects
				(font
					(size 1.016 1.016)
					(thickness 0.1524)
				)
			)
		)
		(duplicate_pad_numbers_are_jumpers no)
		(fp_line
			(start -0.508 -0.9398)
			(end -0.508 0.9398)
			(stroke
				(width 0.1524)
				(type default)
			)
			(layer "F.SilkS")
		)
		(fp_line
			(start 0.508 -0.9398)
			(end -0.508 -0.9398)
			(stroke
				(width 0.1524)
				(type default)
			)
			(layer "F.SilkS")
		)
		(fp_rect
			(start -0.508 0.9398)
			(end 0.508 -0.9398)
			(stroke
				(width 0)
				(type default)
			)
			(fill no)
			(layer "F.CrtYd")
		)
		(fp_rect
			(start -0.508 0.9398)
			(end 0.508 -0.9398)
			(stroke
				(width 0)
				(type default)
			)
			(fill no)
			(layer "F.Fab")
		)
		(pad "1" smd custom
			(at 0 -0.4445)
			(size 0.1397 0.1397)
			(layers "F.Cu" "F.Mask" "F.Paste")
			(net "P12V_IOM")
			(options
				(clearance outline)
				(anchor circle)
			)
			(primitives
				(gr_poly
					(pts
						(arc
							(start -0.1778 -0.2794)
							(mid -0.249642 -0.249642)
							(end -0.2794 -0.1778)
						)
						(arc
							(start -0.2794 0.1778)
							(mid -0.249642 0.249642)
							(end -0.1778 0.2794)
						)
						(arc
							(start 0.1778 0.2794)
							(mid 0.249642 0.249642)
							(end 0.2794 0.1778)
						)
						(arc
							(start 0.2794 -0.1778)
							(mid 0.249642 -0.249642)
							(end 0.1778 -0.2794)
						)
					)
					(width 0)
					(fill yes)
				)
			)
		)
		(pad "2" smd custom
			(at 0 0.4445)
			(size 0.1397 0.1397)
			(layers "F.Cu" "F.Mask" "F.Paste")
			(net "MB0_VCC")
			(options
				(clearance outline)
				(anchor circle)
			)
			(primitives
				(gr_poly
					(pts
						(arc
							(start -0.1778 -0.2794)
							(mid -0.249642 -0.249642)
							(end -0.2794 -0.1778)
						)
						(arc
							(start -0.2794 0.1778)
							(mid -0.249642 0.249642)
							(end -0.1778 0.2794)
						)
						(arc
							(start 0.1778 0.2794)
							(mid 0.249642 0.249642)
							(end 0.2794 0.1778)
						)
						(arc
							(start 0.2794 -0.1778)
							(mid 0.249642 -0.249642)
							(end 0.1778 -0.2794)
						)
					)
					(width 0)
					(fill yes)
				)
			)
		)
	)
	(footprint ""
		(layer "F.Cu")
		(at 149.29993 -78.000098)
		(property "Reference" ""
			(at 0 0 0)
			(layer "F.SilkS")
			(hide yes)
			(effects
				(font
					(size 1.27 1.27)
				)
			)
		)
		(property "Value" "*"
			(at -6.38175 0.19685 0)
			(unlocked yes)
			(layer "F.Fab")
			(hide yes)
			(effects
				(font
					(size 1.016 1.016)
					(thickness 0.1524)
				)
			)
		)
		(duplicate_pad_numbers_are_jumpers no)
		(fp_poly
			(pts
				(arc
					(start 5.0673 0)
					(mid -5.0673 0)
					(end 5.0673 0)
				)
			)
			(stroke
				(width 0)
				(type default)
			)
			(fill no)
			(layer "B.CrtYd")
		)
		(fp_poly
			(pts
				(arc
					(start 5.0673 0)
					(mid -5.0673 0)
					(end 5.0673 0)
				)
			)
			(stroke
				(width 0)
				(type default)
			)
			(fill no)
			(layer "F.CrtYd")
		)
		(fp_poly
			(pts
				(arc
					(start 5.0673 0)
					(mid -5.0673 0)
					(end 5.0673 0)
				)
			)
			(stroke
				(width 0)
				(type default)
			)
			(fill no)
			(layer "B.Fab")
		)
		(fp_poly
			(pts
				(arc
					(start 5.0673 0)
					(mid -5.0673 0)
					(end 5.0673 0)
				)
			)
			(stroke
				(width 0)
				(type default)
			)
			(fill no)
			(layer "F.Fab")
		)
		(pad "1" thru_hole circle
			(at 0 0)
			(size 9.525 9.525)
			(drill 3.5052)
			(layers "*.Cu" "*.Mask")
			(remove_unused_layers no)
			(net "Net_42")
			(clearance -2.5019)
			(thermal_gap 0.3048)
			(padstack
				(mode front_inner_back)
				(layer "Inner"
					(shape circle)
					(size 3.9116 3.9116)
					(clearance 0.3048)
				)
				(layer "B.Cu"
					(shape circle)
					(size 9.525 9.525)
					(clearance -2.5019)
				)
			)
		)
	)
	(footprint ""
		(layer "F.Cu")
		(at 204.216 -110.7694 180)
		(property "Reference" "R544"
			(at 0 0 180)
			(layer "F.SilkS")
			(hide yes)
			(effects
				(font
					(size 1.27 1.27)
				)
			)
		)
		(property "Value" "4K7R2F-GP"
			(at 0.064008 -3.993896 180)
			(unlocked yes)
			(layer "F.Fab")
			(hide yes)
			(effects
				(font
					(size 1.016 1.016)
					(thickness 0.1524)
				)
			)
		)
		(property "Device Type" "R402H16"
			(at 0.064008 -5.517896 180)
			(unlocked yes)
			(layer "F.Fab")
			(hide yes)
			(effects
				(font
					(size 1.016 1.016)
					(thickness 0.1524)
				)
			)
		)
		(duplicate_pad_numbers_are_jumpers no)
		(fp_line
			(start 0.508 -0.9398)
			(end -0.508 -0.9398)
			(stroke
				(width 0.1524)
				(type default)
			)
			(layer "F.SilkS")
		)
		(fp_line
			(start -0.508 -0.9398)
			(end -0.508 0.9398)
			(stroke
				(width 0.1524)
				(type default)
			)
			(layer "F.SilkS")
		)
		(fp_rect
			(start -0.508 0.9398)
			(end 0.508 -0.9398)
			(stroke
				(width 0)
				(type default)
			)
			(fill no)
			(layer "F.CrtYd")
		)
		(fp_rect
			(start -0.508 0.9398)
			(end 0.508 -0.9398)
			(stroke
				(width 0)
				(type default)
			)
			(fill no)
			(layer "F.Fab")
		)
		(pad "1" smd custom
			(at 0 -0.4445 180)
			(size 0.1397 0.1397)
			(layers "F.Cu" "F.Mask" "F.Paste")
			(net "TEMP_2_A1")
			(options
				(clearance outline)
				(anchor circle)
			)
			(primitives
				(gr_poly
					(pts
						(arc
							(start -0.1778 -0.2794)
							(mid -0.249642 -0.249642)
							(end -0.2794 -0.1778)
						)
						(arc
							(start -0.2794 0.1778)
							(mid -0.249642 0.249642)
							(end -0.1778 0.2794)
						)
						(arc
							(start 0.1778 0.2794)
							(mid 0.249642 0.249642)
							(end 0.2794 0.1778)
						)
						(arc
							(start 0.2794 -0.1778)
							(mid 0.249642 -0.249642)
							(end 0.1778 -0.2794)
						)
					)
					(width 0)
					(fill yes)
				)
			)
		)
		(pad "2" smd custom
			(at 0 0.4445 180)
			(size 0.1397 0.1397)
			(layers "F.Cu" "F.Mask" "F.Paste")
			(net "GND")
			(options
				(clearance outline)
				(anchor circle)
			)
			(primitives
				(gr_poly
					(pts
						(arc
							(start -0.1778 -0.2794)
							(mid -0.249642 -0.249642)
							(end -0.2794 -0.1778)
						)
						(arc
							(start -0.2794 0.1778)
							(mid -0.249642 0.249642)
							(end -0.1778 0.2794)
						)
						(arc
							(start 0.1778 0.2794)
							(mid 0.249642 0.249642)
							(end 0.2794 0.1778)
						)
						(arc
							(start 0.2794 -0.1778)
							(mid 0.249642 -0.249642)
							(end 0.1778 -0.2794)
						)
					)
					(width 0)
					(fill yes)
				)
			)
		)
	)
	(footprint ""
		(layer "F.Cu")
		(at 202.946 -110.7694 180)
		(property "Reference" "R555"
			(at 0 0 180)
			(layer "F.SilkS")
			(hide yes)
			(effects
				(font
					(size 1.27 1.27)
				)
			)
		)
		(property "Value" "4K7R2F-GP"
			(at 0.064008 -3.993896 180)
			(unlocked yes)
			(layer "F.Fab")
			(hide yes)
			(effects
				(font
					(size 1.016 1.016)
					(thickness 0.1524)
				)
			)
		)
		(property "Device Type" "R402H16"
			(at 0.064008 -5.517896 180)
			(unlocked yes)
			(layer "F.Fab")
			(hide yes)
			(effects
				(font
					(size 1.016 1.016)
					(thickness 0.1524)
				)
			)
		)
		(duplicate_pad_numbers_are_jumpers no)
		(fp_line
			(start 0.508 -0.9398)
			(end -0.508 -0.9398)
			(stroke
				(width 0.1524)
				(type default)
			)
			(layer "F.SilkS")
		)
		(fp_line
			(start -0.508 -0.9398)
			(end -0.508 0.9398)
			(stroke
				(width 0.1524)
				(type default)
			)
			(layer "F.SilkS")
		)
		(fp_rect
			(start -0.508 0.9398)
			(end 0.508 -0.9398)
			(stroke
				(width 0)
				(type default)
			)
			(fill no)
			(layer "F.CrtYd")
		)
		(fp_rect
			(start -0.508 0.9398)
			(end 0.508 -0.9398)
			(stroke
				(width 0)
				(type default)
			)
			(fill no)
			(layer "F.Fab")
		)
		(pad "1" smd custom
			(at 0 -0.4445 180)
			(size 0.1397 0.1397)
			(layers "F.Cu" "F.Mask" "F.Paste")
			(net "TEMP_2_A0")
			(options
				(clearance outline)
				(anchor circle)
			)
			(primitives
				(gr_poly
					(pts
						(arc
							(start -0.1778 -0.2794)
							(mid -0.249642 -0.249642)
							(end -0.2794 -0.1778)
						)
						(arc
							(start -0.2794 0.1778)
							(mid -0.249642 0.249642)
							(end -0.1778 0.2794)
						)
						(arc
							(start 0.1778 0.2794)
							(mid 0.249642 0.249642)
							(end 0.2794 0.1778)
						)
						(arc
							(start 0.2794 -0.1778)
							(mid 0.249642 -0.249642)
							(end 0.1778 -0.2794)
						)
					)
					(width 0)
					(fill yes)
				)
			)
		)
		(pad "2" smd custom
			(at 0 0.4445 180)
			(size 0.1397 0.1397)
			(layers "F.Cu" "F.Mask" "F.Paste")
			(net "GND")
			(options
				(clearance outline)
				(anchor circle)
			)
			(primitives
				(gr_poly
					(pts
						(arc
							(start -0.1778 -0.2794)
							(mid -0.249642 -0.249642)
							(end -0.2794 -0.1778)
						)
						(arc
							(start -0.2794 0.1778)
							(mid -0.249642 0.249642)
							(end -0.1778 0.2794)
						)
						(arc
							(start 0.1778 0.2794)
							(mid 0.249642 0.249642)
							(end 0.2794 0.1778)
						)
						(arc
							(start 0.2794 -0.1778)
							(mid 0.249642 -0.249642)
							(end 0.1778 -0.2794)
						)
					)
					(width 0)
					(fill yes)
				)
			)
		)
	)
)
